# LPDDR4 testbed — KiCad project settings (.kicad_pro: net classes, design rules, text variables)
{
  "board": {
    "3dviewports": [],
    "design_settings": {
      "defaults": {
        "apply_defaults_to_fp_fields": false,
        "apply_defaults_to_fp_shapes": false,
        "apply_defaults_to_fp_text": false,
        "board_outline_line_width": 0.05,
        "copper_line_width": 0.2,
        "copper_text_italic": false,
        "copper_text_size_h": 1.5,
        "copper_text_size_v": 1.5,
        "copper_text_thickness": 0.3,
        "copper_text_upright": false,
        "courtyard_line_width": 0.05,
        "dimension_precision": 4,
        "dimension_units": 3,
        "dimensions": {
          "arrow_length": 1270000,
          "extension_offset": 500000,
          "keep_text_aligned": true,
          "suppress_zeroes": false,
          "text_position": 0,
          "units_format": 1
        },
        "fab_line_width": 0.1,
        "fab_text_italic": false,
        "fab_text_size_h": 1.0,
        "fab_text_size_v": 1.0,
        "fab_text_thickness": 0.15,
        "fab_text_upright": false,
        "other_line_width": 0.1,
        "other_text_italic": false,
        "other_text_size_h": 1.0,
        "other_text_size_v": 1.0,
        "other_text_thickness": 0.15,
        "other_text_upright": false,
        "pads": {
          "drill": 0.0,
          "height": 2.5,
          "width": 0.35
        },
        "silk_line_width": 0.12,
        "silk_text_italic": false,
        "silk_text_size_h": 1.0,
        "silk_text_size_v": 1.0,
        "silk_text_thickness": 0.15,
        "silk_text_upright": false,
        "zones": {
          "45_degree_only": false,
          "min_clearance": 0.15
        }
      },
      "diff_pair_dimensions": [
        {
          "gap": 0.0,
          "via_gap": 0.0,
          "width": 0.0
        }
      ],
      "drc_exclusions": [],
      "meta": {
        "filename": "board_design_settings.json",
        "version": 2
      },
      "rule_severities": {
        "annular_width": "error",
        "clearance": "error",
        "connection_width": "warning",
        "copper_edge_clearance": "ignore",
        "copper_sliver": "warning",
        "courtyards_overlap": "error",
        "creepage": "error",
        "diff_pair_gap_out_of_range": "error",
        "diff_pair_uncoupled_length_too_long": "error",
        "drill_out_of_range": "error",
        "duplicate_footprints": "warning",
        "extra_footprint": "warning",
        "footprint": "error",
        "footprint_filters_mismatch": "ignore",
        "footprint_symbol_mismatch": "warning",
        "footprint_type_mismatch": "error",
        "hole_clearance": "error",
        "hole_near_hole": "error",
        "hole_to_hole": "error",
        "holes_co_located": "warning",
        "invalid_outline": "error",
        "isolated_copper": "warning",
        "item_on_disabled_layer": "error",
        "items_not_allowed": "error",
        "length_out_of_range": "error",
        "lib_footprint_issues": "ignore",
        "lib_footprint_mismatch": "ignore",
        "malformed_courtyard": "error",
        "microvia_drill_out_of_range": "error",
        "mirrored_text_on_front_layer": "warning",
        "missing_courtyard": "ignore",
        "missing_footprint": "warning",
        "net_conflict": "warning",
        "nonmirrored_text_on_back_layer": "warning",
        "npth_inside_courtyard": "ignore",
        "padstack": "error",
        "pth_inside_courtyard": "ignore",
        "shorting_items": "error",
        "silk_edge_clearance": "warning",
        "silk_over_copper": "ignore",
        "silk_overlap": "ignore",
        "skew_out_of_range": "error",
        "solder_mask_bridge": "error",
        "starved_thermal": "error",
        "text_height": "warning",
        "text_on_edge_cuts": "error",
        "text_thickness": "warning",
        "through_hole_pad_without_hole": "error",
        "too_many_vias": "error",
        "track_angle": "error",
        "track_dangling": "warning",
        "track_segment_length": "error",
        "track_width": "error",
        "tracks_crossing": "error",
        "unconnected_items": "error",
        "unresolved_variable": "error",
        "via_dangling": "warning",
        "zones_intersect": "error"
      },
      "rule_severitieslegacy_courtyards_overlap": true,
      "rule_severitieslegacy_no_courtyard_defined": false,
      "rules": {
        "allow_blind_buried_vias": false,
        "allow_microvias": false,
        "max_error": 0.005,
        "min_clearance": 0.1,
        "min_connection": 0.0,
        "min_copper_edge_clearance": 0.075,
        "min_groove_width": 0.0,
        "min_hole_clearance": 0.2,
        "min_hole_to_hole": 0.25,
        "min_microvia_diameter": 0.2,
        "min_microvia_drill": 0.1,
        "min_resolved_spokes": 2,
        "min_silk_clearance": 0.0,
        "min_text_height": 0.6,
        "min_text_thickness": 0.08,
        "min_through_hole_diameter": 0.15,
        "min_track_width": 0.1,
        "min_via_annular_width": 0.125,
        "min_via_diameter": 0.4,
        "solder_mask_to_copper_clearance": 0.0,
        "use_height_for_length_calcs": true
      },
      "teardrop_options": [
        {
          "td_onpthpad": true,
          "td_onroundshapesonly": false,
          "td_onsmdpad": true,
          "td_ontrackend": false,
          "td_onvia": true
        }
      ],
      "teardrop_parameters": [
        {
          "td_allow_use_two_tracks": true,
          "td_curve_segcount": 1,
          "td_height_ratio": 1.0,
          "td_length_ratio": 0.5,
          "td_maxheight": 2.0,
          "td_maxlen": 1.0,
          "td_on_pad_in_zone": false,
          "td_target_name": "td_round_shape",
          "td_width_to_size_filter_ratio": 0.9
        },
        {
          "td_allow_use_two_tracks": true,
          "td_curve_segcount": 1,
          "td_height_ratio": 1.0,
          "td_length_ratio": 0.5,
          "td_maxheight": 2.0,
          "td_maxlen": 1.0,
          "td_on_pad_in_zone": false,
          "td_target_name": "td_rect_shape",
          "td_width_to_size_filter_ratio": 0.9
        },
        {
          "td_allow_use_two_tracks": true,
          "td_curve_segcount": 1,
          "td_height_ratio": 1.0,
          "td_length_ratio": 0.5,
          "td_maxheight": 2.0,
          "td_maxlen": 1.0,
          "td_on_pad_in_zone": false,
          "td_target_name": "td_track_end",
          "td_width_to_size_filter_ratio": 0.9
        }
      ],
      "track_widths": [
        0.0,
        0.1,
        0.2
      ],
      "tuning_pattern_settings": {
        "diff_pair_defaults": {
          "corner_radius_percentage": 80,
          "corner_style": 1,
          "max_amplitude": 1.0,
          "min_amplitude": 0.2,
          "single_sided": false,
          "spacing": 1.0
        },
        "diff_pair_skew_defaults": {
          "corner_radius_percentage": 80,
          "corner_style": 1,
          "max_amplitude": 1.0,
          "min_amplitude": 0.2,
          "single_sided": false,
          "spacing": 0.6
        },
        "single_track_defaults": {
          "corner_radius_percentage": 80,
          "corner_style": 1,
          "max_amplitude": 1.0,
          "min_amplitude": 0.2,
          "single_sided": false,
          "spacing": 0.6
        }
      },
      "via_dimensions": [
        {
          "diameter": 0.0,
          "drill": 0.0
        },
        {
          "diameter": 0.4,
          "drill": 0.15
        }
      ],
      "zones_allow_external_fillets": false,
      "zones_use_no_outline": true
    },
    "ipc2581": {
      "dist": "",
      "distpn": "",
      "internal_id": "",
      "mfg": "",
      "mpn": ""
    },
    "layer_pairs": [],
    "layer_presets": [],
    "viewports": []
  },
  "boards": [],
  "cvpcb": {
    "equivalence_files": []
  },
  "erc": {
    "erc_exclusions": [],
    "meta": {
      "version": 0
    },
    "pin_map": [
      [
        0,
        0,
        0,
        0,
        0,
        0,
        1,
        0,
        0,
        0,
        0,
        2
      ],
      [
        0,
        2,
        0,
        1,
        0,
        0,
        1,
        0,
        2,
        2,
        2,
        2
      ],
      [
        0,
        0,
        0,
        0,
        0,
        0,
        1,
        0,
        1,
        0,
        1,
        2
      ],
      [
        0,
        1,
        0,
        0,
        0,
        0,
        1,
        1,
        2,
        1,
        1,
        2
      ],
      [
        0,
        0,
        0,
        0,
        0,
        0,
        1,
        0,
        0,
        0,
        0,
        2
      ],
      [
        0,
        0,
        0,
        0,
        0,
        0,
        0,
        0,
        0,
        0,
        0,
        2
      ],
      [
        1,
        1,
        1,
        1,
        1,
        0,
        1,
        1,
        1,
        1,
        1,
        2
      ],
      [
        0,
        0,
        0,
        1,
        0,
        0,
        1,
        0,
        0,
        0,
        0,
        2
      ],
      [
        0,
        2,
        1,
        2,
        0,
        0,
        1,
        0,
        2,
        2,
        2,
        2
      ],
      [
        0,
        2,
        0,
        1,
        0,
        0,
        1,
        0,
        2,
        0,
        0,
        2
      ],
      [
        0,
        2,
        1,
        1,
        0,
        0,
        1,
        0,
        2,
        0,
        0,
        2
      ],
      [
        2,
        2,
        2,
        2,
        2,
        2,
        2,
        2,
        2,
        2,
        2,
        2
      ]
    ],
    "rule_severities": {
      "bus_definition_conflict": "error",
      "bus_entry_needed": "error",
      "bus_to_bus_conflict": "error",
      "bus_to_net_conflict": "error",
      "conflicting_netclasses": "error",
      "different_unit_footprint": "error",
      "different_unit_net": "error",
      "duplicate_reference": "error",
      "duplicate_sheet_names": "error",
      "endpoint_off_grid": "ignore",
      "extra_units": "error",
      "footprint_filter": "ignore",
      "footprint_link_issues": "warning",
      "four_way_junction": "ignore",
      "global_label_dangling": "warning",
      "hier_label_mismatch": "error",
      "label_dangling": "error",
      "label_multiple_wires": "warning",
      "lib_symbol_issues": "ignore",
      "lib_symbol_mismatch": "warning",
      "missing_bidi_pin": "warning",
      "missing_input_pin": "warning",
      "missing_power_pin": "error",
      "missing_unit": "warning",
      "multiple_net_names": "warning",
      "net_not_bus_member": "warning",
      "no_connect_connected": "ignore",
      "no_connect_dangling": "warning",
      "pin_not_connected": "error",
      "pin_not_driven": "error",
      "pin_to_pin": "warning",
      "power_pin_not_driven": "error",
      "same_local_global_label": "warning",
      "similar_label_and_power": "warning",
      "similar_labels": "warning",
      "similar_power": "warning",
      "simulation_model_issue": "ignore",
      "single_global_label": "ignore",
      "unannotated": "error",
      "unconnected_wire_endpoint": "warning",
      "undefined_netclass": "error",
      "unit_value_mismatch": "error",
      "unresolved_variable": "error",
      "wire_dangling": "error"
    }
  },
  "libraries": {
    "pinned_footprint_libs": [],
    "pinned_symbol_libs": []
  },
  "meta": {
    "filename": "lpddr4-testbed.kicad_pro",
    "version": 3
  },
  "net_settings": {
    "classes": [
      {
        "bus_width": 12,
        "clearance": 0.1,
        "diff_pair_gap": 0.25,
        "diff_pair_via_gap": 0.25,
        "diff_pair_width": 0.2,
        "line_style": 0,
        "microvia_diameter": 0.3,
        "microvia_drill": 0.1,
        "name": "Default",
        "pcb_color": "rgba(0, 0, 0, 0.000)",
        "priority": 2147483647,
        "schematic_color": "rgba(0, 0, 0, 0.000)",
        "track_width": 0.1,
        "via_diameter": 0.4,
        "via_drill": 0.15,
        "wire_width": 6
      }
    ],
    "meta": {
      "version": 4
    },
    "net_colors": null,
    "netclass_assignments": null,
    "netclass_patterns": []
  },
  "pcbnew": {
    "last_paths": {
      "gencad": "",
      "idf": "",
      "netlist": "",
      "plot": "",
      "pos_files": "",
      "specctra_dsn": "",
      "step": "",
      "svg": "",
      "vrml": ""
    },
    "page_layout_descr_file": ""
  },
  "schematic": {
    "annotate_start_num": 0,
    "bom_export_filename": "${PROJECTNAME}.csv",
    "bom_fmt_presets": [],
    "bom_fmt_settings": {
      "field_delimiter": ",",
      "keep_line_breaks": false,
      "keep_tabs": false,
      "name": "CSV",
      "ref_delimiter": ",",
      "ref_range_delimiter": "",
      "string_delimiter": "\""
    },
    "bom_presets": [],
    "bom_settings": {
      "exclude_dnp": false,
      "fields_ordered": [
        {
          "group_by": false,
          "label": "Reference",
          "name": "Reference",
          "show": true
        },
        {
          "group_by": false,
          "label": "Qty",
          "name": "${QUANTITY}",
          "show": true
        },
        {
          "group_by": true,
          "label": "Value",
          "name": "Value",
          "show": true
        },
        {
          "group_by": true,
          "label": "DNP",
          "name": "${DNP}",
          "show": true
        },
        {
          "group_by": true,
          "label": "Exclude from BOM",
          "name": "${EXCLUDE_FROM_BOM}",
          "show": true
        },
        {
          "group_by": true,
          "label": "Exclude from Board",
          "name": "${EXCLUDE_FROM_BOARD}",
          "show": true
        },
        {
          "group_by": true,
          "label": "Footprint",
          "name": "Footprint",
          "show": true
        },
        {
          "group_by": false,
          "label": "Datasheet",
          "name": "Datasheet",
          "show": true
        }
      ],
      "filter_string": "",
      "group_symbols": true,
      "include_excluded_from_bom": true,
      "name": "Default Editing",
      "sort_asc": true,
      "sort_field": "Reference"
    },
    "connection_grid_size": 50.0,
    "drawing": {
      "dashed_lines_dash_length_ratio": 12.0,
      "dashed_lines_gap_length_ratio": 3.0,
      "default_line_thickness": 6.0,
      "default_text_size": 50.0,
      "field_names": [],
      "intersheets_ref_own_page": false,
      "intersheets_ref_prefix": "",
      "intersheets_ref_short": false,
      "intersheets_ref_show": false,
      "intersheets_ref_suffix": "",
      "junction_size_choice": 3,
      "label_size_ratio": 0.25,
      "operating_point_overlay_i_precision": 3,
      "operating_point_overlay_i_range": "~A",
      "operating_point_overlay_v_precision": 3,
      "operating_point_overlay_v_range": "~V",
      "overbar_offset_ratio": 1.23,
      "pin_symbol_size": 0.0,
      "text_offset_ratio": 0.08
    },
    "legacy_lib_dir": "",
    "legacy_lib_list": [],
    "meta": {
      "version": 1
    },
    "net_format_name": "",
    "ngspice": {
      "fix_include_paths": true,
      "fix_passive_vals": false,
      "meta": {
        "version": 0
      },
      "model_mode": 0,
      "workbook_filename": ""
    },
    "page_layout_descr_file": "",
    "plot_directory": "",
    "space_save_all_events": true,
    "spice_adjust_passive_values": false,
    "spice_current_sheet_as_root": false,
    "spice_external_command": "spice \"%I\"",
    "spice_model_current_sheet_as_root": true,
    "spice_save_all_currents": false,
    "spice_save_all_dissipations": false,
    "spice_save_all_voltages": false,
    "subpart_first_id": 65,
    "subpart_id_separator": 0
  },
  "sheets": [
    [
      "",
      "Root"
    ],
    [
      "",
      "EEPROM"
    ],
    [
      "",
      "SODIMM"
    ],
    [
      "",
      "LPDDR4"
    ]
  ],
  "text_variables": {}
}
